(kicad_pcb
	(version 20260206)
	(generator "pcbnew")
	(generator_version "10.0")
	(general
		(thickness 1.6)
		(legacy_teardrops no)
	)
	(paper "A4")
	(title_block
		(title "netronome-mezz — pcbd0082-001_rev01_jul9_a.brd")
		(comment 1 "Open CloudServer (Microsoft) / footprint 225 of 714 (U1), pads 812-928 of 1022")
	)
	(layers
		(0 "F.Cu" signal "TOP")
		(4 "In1.Cu" signal "02_GND")
		(6 "In2.Cu" signal "03_SIG")
		(8 "In3.Cu" signal "04_SIG")
		(10 "In4.Cu" signal "05_GND")
		(12 "In5.Cu" signal "06_PWR1")
		(14 "In6.Cu" signal "07_SIG")
		(16 "In7.Cu" signal "08_SIG")
		(18 "In8.Cu" signal "09_GND")
		(2 "B.Cu" signal "BOTTOM")
		(9 "F.Adhes" user "F.Adhesive")
		(11 "B.Adhes" user "B.Adhesive")
		(13 "F.Paste" user "Package Geometry/Pastemask Top")
		(15 "B.Paste" user "Package Geometry/Pastemask Bottom")
		(5 "F.SilkS" user "Ref Des/Silkscreen Top")
		(7 "B.SilkS" user "Ref Des/Silkscreen Bottom")
		(1 "F.Mask" user "Board Geometry/Soldermask Top")
		(3 "B.Mask" user "Board Geometry/Soldermask Bottom")
		(17 "Dwgs.User" user "User.Drawings")
		(19 "Cmts.User" user "User.Comments")
		(21 "Eco1.User" user "User.Eco1")
		(23 "Eco2.User" user "User.Eco2")
		(25 "Edge.Cuts" user "Board Geometry/Outline")
		(27 "Margin" user)
		(31 "F.CrtYd" user "Package Geometry/Place Bound Top")
		(29 "B.CrtYd" user "Package Geometry/Place Bound Bottom")
		(35 "F.Fab" user "Ref Des/Assembly Top")
		(33 "B.Fab" user "Ref Des/Assembly Bottom")
		(45 "User.4" user "COMPVAL_TYPE_BOTTOM")
	)
	(footprint ""
		(layer "F.Cu")
		(at 54.737 18.542 180)
		(property "Reference" "U1"
			(at -12.192 17.9705 0)
			(unlocked yes)
			(layer "F.SilkS")
			(effects
				(font
					(size 1.27 0.9652)
					(thickness 0.1524)
				)
				(justify left)
			)
		)
		(property "Value" "*"
			(at -0.4826 1.74879 180)
			(unlocked yes)
			(layer "F.Fab")
			(hide yes)
			(effects
				(font
					(size 1.27 0.9652)
					(thickness 0.000001)
				)
				(justify left)
			)
		)
		(property "Device Type" "ICBG0048"
			(at -0.4826 1.74879 180)
			(unlocked yes)
			(layer "F.Fab")
			(hide yes)
			(effects
				(font
					(size 1.27 0.9652)
					(thickness 0.000001)
				)
				(justify left)
			)
		)
		(duplicate_pad_numbers_are_jumpers no)
		(pad "P14" smd circle
			(at -2.499995 -2.499995 180)
			(size 0.508 0.508)
			(layers "F.Cu" "F.Mask" "F.Paste")
			(net "VDD_CORE")
		)
		(pad "P15" smd circle
			(at -1.499997 -2.499995 180)
			(size 0.508 0.508)
			(layers "F.Cu" "F.Mask" "F.Paste")
			(net "GND")
		)
		(pad "P16" smd circle
			(at -0.499999 -2.499995 180)
			(size 0.508 0.508)
			(layers "F.Cu" "F.Mask" "F.Paste")
			(net "VDD_CORE")
		)
		(pad "P17" smd circle
			(at 0.499999 -2.499995 180)
			(size 0.508 0.508)
			(layers "F.Cu" "F.Mask" "F.Paste")
			(net "GND")
		)
		(pad "P18" smd circle
			(at 1.499997 -2.499995 180)
			(size 0.508 0.508)
			(layers "F.Cu" "F.Mask" "F.Paste")
			(net "VDD_CORE")
		)
		(pad "P19" smd circle
			(at 2.499995 -2.499995 180)
			(size 0.508 0.508)
			(layers "F.Cu" "F.Mask" "F.Paste")
			(net "GND")
		)
		(pad "P20" smd circle
			(at 3.499993 -2.499995 180)
			(size 0.508 0.508)
			(layers "F.Cu" "F.Mask" "F.Paste")
			(net "VDD_CORE")
		)
		(pad "P21" smd circle
			(at 4.499991 -2.499995 180)
			(size 0.508 0.508)
			(layers "F.Cu" "F.Mask" "F.Paste")
			(net "GND")
		)
		(pad "P22" smd circle
			(at 5.499989 -2.499995 180)
			(size 0.508 0.508)
			(layers "F.Cu" "F.Mask" "F.Paste")
			(net "VDD_CORE")
		)
		(pad "P23" smd circle
			(at 6.500012 -2.499995 180)
			(size 0.508 0.508)
			(layers "F.Cu" "F.Mask" "F.Paste")
			(net "GND")
		)
		(pad "P24" smd circle
			(at 7.50001 -2.499995 180)
			(size 0.508 0.508)
			(layers "F.Cu" "F.Mask" "F.Paste")
			(net "VDD_CORE")
		)
		(pad "P25" smd circle
			(at 8.500008 -2.499995 180)
			(size 0.508 0.508)
			(layers "F.Cu" "F.Mask" "F.Paste")
			(net "GND")
		)
		(pad "P26" smd circle
			(at 9.500006 -2.499995 180)
			(size 0.508 0.508)
			(layers "F.Cu" "F.Mask" "F.Paste")
			(net "VDD_CORE")
		)
		(pad "P27" smd circle
			(at 10.500004 -2.499995 180)
			(size 0.508 0.508)
			(layers "F.Cu" "F.Mask" "F.Paste")
			(net "GND")
		)
		(pad "P28" smd circle
			(at 11.500002 -2.499995 180)
			(size 0.508 0.508)
			(layers "F.Cu" "F.Mask" "F.Paste")
			(net "VDD_CORE_PGOOD")
		)
		(pad "P29" smd circle
			(at 12.5 -2.499995 180)
			(size 0.508 0.508)
			(layers "F.Cu" "F.Mask" "F.Paste")
			(net "NFP_ARM_SPI_FLASH_MISO")
		)
		(pad "P30" smd circle
			(at 13.499998 -2.499995 180)
			(size 0.508 0.508)
			(layers "F.Cu" "F.Mask" "F.Paste")
			(net "PCIE0_RST_L")
		)
		(pad "P31" smd circle
			(at 14.499996 -2.499995 180)
			(size 0.508 0.508)
			(layers "F.Cu" "F.Mask" "F.Paste")
			(net "GND")
		)
		(pad "P32" smd circle
			(at 15.499994 -2.499995 180)
			(size 0.508 0.508)
			(layers "F.Cu" "F.Mask" "F.Paste")
			(net "_NFP_PCIE1_RESET_OUT_L")
		)
		(pad "R1" smd circle
			(at -15.499994 -1.499997 180)
			(size 0.508 0.508)
			(layers "F.Cu" "F.Mask" "F.Paste")
			(net "_NC_DDR0_32B_DQ2")
		)
		(pad "R2" smd circle
			(at -14.499996 -1.499997 180)
			(size 0.508 0.508)
			(layers "F.Cu" "F.Mask" "F.Paste")
			(net "_NC_DDR0_32B_DQ5")
		)
		(pad "R3" smd circle
			(at -13.499998 -1.499997 180)
			(size 0.508 0.508)
			(layers "F.Cu" "F.Mask" "F.Paste")
			(net "_NC_DDR0_32B_DQ1")
		)
		(pad "R4" smd circle
			(at -12.5 -1.499997 180)
			(size 0.508 0.508)
			(layers "F.Cu" "F.Mask" "F.Paste")
			(net "_NC_DDR0_32B_DQ0")
		)
		(pad "R5" smd circle
			(at -11.500002 -1.499997 180)
			(size 0.508 0.508)
			(layers "F.Cu" "F.Mask" "F.Paste")
			(net "DDR0_32A_CB5")
		)
		(pad "R6" smd circle
			(at -10.500004 -1.499997 180)
			(size 0.508 0.508)
			(layers "F.Cu" "F.Mask" "F.Paste")
			(net "DDR0_32A_DM4")
		)
		(pad "R7" smd circle
			(at -9.500006 -1.499997 180)
			(size 0.508 0.508)
			(layers "F.Cu" "F.Mask" "F.Paste")
			(net "DDR0_32A_A14")
		)
		(pad "R8" smd circle
			(at -8.500008 -1.499997 180)
			(size 0.508 0.508)
			(layers "F.Cu" "F.Mask" "F.Paste")
			(net "DDR0_32A_A11")
		)
		(pad "R9" smd circle
			(at -7.50001 -1.499997 180)
			(size 0.508 0.508)
			(layers "F.Cu" "F.Mask" "F.Paste")
			(net "DDR0_32A_A7")
		)
		(pad "R10" smd circle
			(at -6.500012 -1.499997 180)
			(size 0.508 0.508)
			(layers "F.Cu" "F.Mask" "F.Paste")
			(net "_NC_NFP_DDR0_32A_PLL_DTO1")
		)
		(pad "R11" smd circle
			(at -5.499989 -1.499997 180)
			(size 0.508 0.508)
			(layers "F.Cu" "F.Mask" "F.Paste")
			(net "VDD_CORE")
		)
		(pad "R12" smd circle
			(at -4.499991 -1.499997 180)
			(size 0.508 0.508)
			(layers "F.Cu" "F.Mask" "F.Paste")
			(net "GND")
		)
		(pad "R13" smd circle
			(at -3.499993 -1.499997 180)
			(size 0.508 0.508)
			(layers "F.Cu" "F.Mask" "F.Paste")
			(net "VDD_CORE")
		)
		(pad "R14" smd circle
			(at -2.499995 -1.499997 180)
			(size 0.508 0.508)
			(layers "F.Cu" "F.Mask" "F.Paste")
			(net "GND")
		)
		(pad "R15" smd circle
			(at -1.499997 -1.499997 180)
			(size 0.508 0.508)
			(layers "F.Cu" "F.Mask" "F.Paste")
			(net "VDD_CORE")
		)
		(pad "R16" smd circle
			(at -0.499999 -1.499997 180)
			(size 0.508 0.508)
			(layers "F.Cu" "F.Mask" "F.Paste")
			(net "GND")
		)
		(pad "R17" smd circle
			(at 0.499999 -1.499997 180)
			(size 0.508 0.508)
			(layers "F.Cu" "F.Mask" "F.Paste")
			(net "VDD_CORE")
		)
		(pad "R18" smd circle
			(at 1.499997 -1.499997 180)
			(size 0.508 0.508)
			(layers "F.Cu" "F.Mask" "F.Paste")
			(net "GND")
		)
		(pad "R19" smd circle
			(at 2.499995 -1.499997 180)
			(size 0.508 0.508)
			(layers "F.Cu" "F.Mask" "F.Paste")
			(net "VDD_CORE")
		)
		(pad "R20" smd circle
			(at 3.499993 -1.499997 180)
			(size 0.508 0.508)
			(layers "F.Cu" "F.Mask" "F.Paste")
			(net "GND")
		)
		(pad "R21" smd circle
			(at 4.499991 -1.499997 180)
			(size 0.508 0.508)
			(layers "F.Cu" "F.Mask" "F.Paste")
			(net "VDD_CORE")
		)
		(pad "R22" smd circle
			(at 5.499989 -1.499997 180)
			(size 0.508 0.508)
			(layers "F.Cu" "F.Mask" "F.Paste")
			(net "GND")
		)
		(pad "R23" smd circle
			(at 6.500012 -1.499997 180)
			(size 0.508 0.508)
			(layers "F.Cu" "F.Mask" "F.Paste")
			(net "VDD_CORE")
		)
		(pad "R24" smd circle
			(at 7.50001 -1.499997 180)
			(size 0.508 0.508)
			(layers "F.Cu" "F.Mask" "F.Paste")
			(net "GND")
		)
		(pad "R25" smd circle
			(at 8.500008 -1.499997 180)
			(size 0.508 0.508)
			(layers "F.Cu" "F.Mask" "F.Paste")
			(net "VDD_CORE")
		)
		(pad "R26" smd circle
			(at 9.500006 -1.499997 180)
			(size 0.508 0.508)
			(layers "F.Cu" "F.Mask" "F.Paste")
			(net "GND")
		)
		(pad "R27" smd circle
			(at 10.500004 -1.499997 180)
			(size 0.508 0.508)
			(layers "F.Cu" "F.Mask" "F.Paste")
			(net "NFP_CLK_REF_P")
		)
		(pad "R28" smd circle
			(at 11.500002 -1.499997 180)
			(size 0.508 0.508)
			(layers "F.Cu" "F.Mask" "F.Paste")
			(net "NFP_PGOOD4")
		)
		(pad "R29" smd circle
			(at 12.5 -1.499997 180)
			(size 0.508 0.508)
			(layers "F.Cu" "F.Mask" "F.Paste")
			(net "_NFP_ARM_SPI_FLASH_SCK")
		)
		(pad "R30" smd circle
			(at 13.499998 -1.499997 180)
			(size 0.508 0.508)
			(layers "F.Cu" "F.Mask" "F.Paste")
			(net "_NC_SPIX_D3")
		)
		(pad "R31" smd circle
			(at 14.499996 -1.499997 180)
			(size 0.508 0.508)
			(layers "F.Cu" "F.Mask" "F.Paste")
			(net "GND")
		)
		(pad "R32" smd circle
			(at 15.499994 -1.499997 180)
			(size 0.508 0.508)
			(layers "F.Cu" "F.Mask" "F.Paste")
			(net "_NC_NFP_SPIX_SEL3")
		)
		(pad "T1" smd circle
			(at -15.499994 -0.499999 180)
			(size 0.508 0.508)
			(layers "F.Cu" "F.Mask" "F.Paste")
			(net "DDR0_32A_DQS4_N")
		)
		(pad "T2" smd circle
			(at -14.499996 -0.499999 180)
			(size 0.508 0.508)
			(layers "F.Cu" "F.Mask" "F.Paste")
			(net "DDR0_32A_DQS4_P")
		)
		(pad "T3" smd circle
			(at -13.499998 -0.499999 180)
			(size 0.508 0.508)
			(layers "F.Cu" "F.Mask" "F.Paste")
			(net "DDR0_32A_CB7")
		)
		(pad "T4" smd circle
			(at -12.5 -0.499999 180)
			(size 0.508 0.508)
			(layers "F.Cu" "F.Mask" "F.Paste")
			(net "DDR0_32A_CB1")
		)
		(pad "T5" smd circle
			(at -11.500002 -0.499999 180)
			(size 0.508 0.508)
			(layers "F.Cu" "F.Mask" "F.Paste")
			(net "DDR0_32A_CB3")
		)
		(pad "T6" smd circle
			(at -10.500004 -0.499999 180)
			(size 0.508 0.508)
			(layers "F.Cu" "F.Mask" "F.Paste")
			(net "DDR0_32A_CB4")
		)
		(pad "T7" smd circle
			(at -9.500006 -0.499999 180)
			(size 0.508 0.508)
			(layers "F.Cu" "F.Mask" "F.Paste")
			(net "DDR0_32A_A1")
		)
		(pad "T8" smd circle
			(at -8.500008 -0.499999 180)
			(size 0.508 0.508)
			(layers "F.Cu" "F.Mask" "F.Paste")
			(net "DDR0_32A_A3")
		)
		(pad "T9" smd circle
			(at -7.50001 -0.499999 180)
			(size 0.508 0.508)
			(layers "F.Cu" "F.Mask" "F.Paste")
			(net "DDR0_32A_A5")
		)
		(pad "T10" smd circle
			(at -6.500012 -0.499999 180)
			(size 0.508 0.508)
			(layers "F.Cu" "F.Mask" "F.Paste")
			(net "DDR_VDDQ")
		)
		(pad "T11" smd circle
			(at -5.499989 -0.499999 180)
			(size 0.508 0.508)
			(layers "F.Cu" "F.Mask" "F.Paste")
			(net "GND")
		)
		(pad "T12" smd circle
			(at -4.499991 -0.499999 180)
			(size 0.508 0.508)
			(layers "F.Cu" "F.Mask" "F.Paste")
			(net "VDD_CORE")
		)
		(pad "T13" smd circle
			(at -3.499993 -0.499999 180)
			(size 0.508 0.508)
			(layers "F.Cu" "F.Mask" "F.Paste")
			(net "GND")
		)
		(pad "T14" smd circle
			(at -2.499995 -0.499999 180)
			(size 0.508 0.508)
			(layers "F.Cu" "F.Mask" "F.Paste")
			(net "VDD_CORE")
		)
		(pad "T15" smd circle
			(at -1.499997 -0.499999 180)
			(size 0.508 0.508)
			(layers "F.Cu" "F.Mask" "F.Paste")
			(net "GND")
		)
		(pad "T16" smd circle
			(at -0.499999 -0.499999 180)
			(size 0.508 0.508)
			(layers "F.Cu" "F.Mask" "F.Paste")
			(net "VDD_CORE")
		)
		(pad "T17" smd circle
			(at 0.499999 -0.499999 180)
			(size 0.508 0.508)
			(layers "F.Cu" "F.Mask" "F.Paste")
			(net "GND")
		)
		(pad "T18" smd circle
			(at 1.499997 -0.499999 180)
			(size 0.508 0.508)
			(layers "F.Cu" "F.Mask" "F.Paste")
			(net "VDD_CORE")
		)
		(pad "T19" smd circle
			(at 2.499995 -0.499999 180)
			(size 0.508 0.508)
			(layers "F.Cu" "F.Mask" "F.Paste")
			(net "GND")
		)
		(pad "T20" smd circle
			(at 3.499993 -0.499999 180)
			(size 0.508 0.508)
			(layers "F.Cu" "F.Mask" "F.Paste")
			(net "VDD_CORE")
		)
		(pad "T21" smd circle
			(at 4.499991 -0.499999 180)
			(size 0.508 0.508)
			(layers "F.Cu" "F.Mask" "F.Paste")
			(net "GND")
		)
		(pad "T22" smd circle
			(at 5.499989 -0.499999 180)
			(size 0.508 0.508)
			(layers "F.Cu" "F.Mask" "F.Paste")
			(net "VDD_CORE")
		)
		(pad "T23" smd circle
			(at 6.500012 -0.499999 180)
			(size 0.508 0.508)
			(layers "F.Cu" "F.Mask" "F.Paste")
			(net "GND")
		)
		(pad "T24" smd circle
			(at 7.50001 -0.499999 180)
			(size 0.508 0.508)
			(layers "F.Cu" "F.Mask" "F.Paste")
			(net "VDD_CORE")
		)
		(pad "T25" smd circle
			(at 8.500008 -0.499999 180)
			(size 0.508 0.508)
			(layers "F.Cu" "F.Mask" "F.Paste")
			(net "GND")
		)
		(pad "T26" smd circle
			(at 9.500006 -0.499999 180)
			(size 0.508 0.508)
			(layers "F.Cu" "F.Mask" "F.Paste")
			(net "VDD_CORE")
		)
		(pad "T27" smd circle
			(at 10.500004 -0.499999 180)
			(size 0.508 0.508)
			(layers "F.Cu" "F.Mask" "F.Paste")
			(net "NFP_CLK_REF_N")
		)
		(pad "T28" smd circle
			(at 11.500002 -0.499999 180)
			(size 0.508 0.508)
			(layers "F.Cu" "F.Mask" "F.Paste")
			(net "GND")
		)
		(pad "T29" smd circle
			(at 12.5 -0.499999 180)
			(size 0.508 0.508)
			(layers "F.Cu" "F.Mask" "F.Paste")
			(net "_NFP_SPI2_SCK")
		)
		(pad "T30" smd circle
			(at 13.499998 -0.499999 180)
			(size 0.508 0.508)
			(layers "F.Cu" "F.Mask" "F.Paste")
			(net "_NC_NFP_SPI3_MOSI")
		)
		(pad "T31" smd circle
			(at 14.499996 -0.499999 180)
			(size 0.508 0.508)
			(layers "F.Cu" "F.Mask" "F.Paste")
			(net "_NFP_CFG_SPI_FLASH_SCK")
		)
		(pad "T32" smd circle
			(at 15.499994 -0.499999 180)
			(size 0.508 0.508)
			(layers "F.Cu" "F.Mask" "F.Paste")
			(net "_NFP_CFG_SPI_FLASH_SEL")
		)
		(pad "U1" smd circle
			(at -15.499994 0.499999 180)
			(size 0.508 0.508)
			(layers "F.Cu" "F.Mask" "F.Paste")
			(net "DDR0_32A_CB6")
		)
		(pad "U2" smd circle
			(at -14.499996 0.499999 180)
			(size 0.508 0.508)
			(layers "F.Cu" "F.Mask" "F.Paste")
			(net "DDR0_32A_CB0")
		)
		(pad "U3" smd circle
			(at -13.499998 0.499999 180)
			(size 0.508 0.508)
			(layers "F.Cu" "F.Mask" "F.Paste")
			(net "DDR_VDDQ")
		)
		(pad "U4" smd circle
			(at -12.5 0.499999 180)
			(size 0.508 0.508)
			(layers "F.Cu" "F.Mask" "F.Paste")
			(net "DDR0_32A_CB2")
		)
		(pad "U5" smd circle
			(at -11.500002 0.499999 180)
			(size 0.508 0.508)
			(layers "F.Cu" "F.Mask" "F.Paste")
			(net "DDR0_32A_DQ25")
		)
		(pad "U6" smd circle
			(at -10.500004 0.499999 180)
			(size 0.508 0.508)
			(layers "F.Cu" "F.Mask" "F.Paste")
			(net "DDR_VDDQ")
		)
		(pad "U7" smd circle
			(at -9.500006 0.499999 180)
			(size 0.508 0.508)
			(layers "F.Cu" "F.Mask" "F.Paste")
			(net "_NC_DDR0_32A_CK1_P")
		)
		(pad "U8" smd circle
			(at -8.500008 0.499999 180)
			(size 0.508 0.508)
			(layers "F.Cu" "F.Mask" "F.Paste")
			(net "_NC_DDR0_32A_CK1_N")
		)
		(pad "U9" smd circle
			(at -7.50001 0.499999 180)
			(size 0.508 0.508)
			(layers "F.Cu" "F.Mask" "F.Paste")
			(net "DDR0_32A_BA0")
		)
		(pad "U10" smd circle
			(at -6.500012 0.499999 180)
			(size 0.508 0.508)
			(layers "F.Cu" "F.Mask" "F.Paste")
			(net "VDDA_PLL")
		)
		(pad "U11" smd circle
			(at -5.499989 0.499999 180)
			(size 0.508 0.508)
			(layers "F.Cu" "F.Mask" "F.Paste")
			(net "VDD_CORE")
		)
		(pad "U12" smd circle
			(at -4.499991 0.499999 180)
			(size 0.508 0.508)
			(layers "F.Cu" "F.Mask" "F.Paste")
			(net "GND")
		)
		(pad "U13" smd circle
			(at -3.499993 0.499999 180)
			(size 0.508 0.508)
			(layers "F.Cu" "F.Mask" "F.Paste")
			(net "VDD_CORE")
		)
		(pad "U14" smd circle
			(at -2.499995 0.499999 180)
			(size 0.508 0.508)
			(layers "F.Cu" "F.Mask" "F.Paste")
			(net "GND")
		)
		(pad "U15" smd circle
			(at -1.499997 0.499999 180)
			(size 0.508 0.508)
			(layers "F.Cu" "F.Mask" "F.Paste")
			(net "VDD_CORE")
		)
		(pad "U16" smd circle
			(at -0.499999 0.499999 180)
			(size 0.508 0.508)
			(layers "F.Cu" "F.Mask" "F.Paste")
			(net "GND")
		)
		(pad "U17" smd circle
			(at 0.499999 0.499999 180)
			(size 0.508 0.508)
			(layers "F.Cu" "F.Mask" "F.Paste")
			(net "VDD_CORE")
		)
		(pad "U18" smd circle
			(at 1.499997 0.499999 180)
			(size 0.508 0.508)
			(layers "F.Cu" "F.Mask" "F.Paste")
			(net "GND")
		)
		(pad "U19" smd circle
			(at 2.499995 0.499999 180)
			(size 0.508 0.508)
			(layers "F.Cu" "F.Mask" "F.Paste")
			(net "VDD_CORE")
		)
		(pad "U20" smd circle
			(at 3.499993 0.499999 180)
			(size 0.508 0.508)
			(layers "F.Cu" "F.Mask" "F.Paste")
			(net "GND")
		)
		(pad "U21" smd circle
			(at 4.499991 0.499999 180)
			(size 0.508 0.508)
			(layers "F.Cu" "F.Mask" "F.Paste")
			(net "VDD_CORE")
		)
		(pad "U22" smd circle
			(at 5.499989 0.499999 180)
			(size 0.508 0.508)
			(layers "F.Cu" "F.Mask" "F.Paste")
			(net "GND")
		)
		(pad "U23" smd circle
			(at 6.500012 0.499999 180)
			(size 0.508 0.508)
			(layers "F.Cu" "F.Mask" "F.Paste")
			(net "VDD_CORE")
		)
		(pad "U24" smd circle
			(at 7.50001 0.499999 180)
			(size 0.508 0.508)
			(layers "F.Cu" "F.Mask" "F.Paste")
			(net "GND")
		)
		(pad "U25" smd circle
			(at 8.500008 0.499999 180)
			(size 0.508 0.508)
			(layers "F.Cu" "F.Mask" "F.Paste")
			(net "VDD_CORE")
		)
		(pad "U26" smd circle
			(at 9.500006 0.499999 180)
			(size 0.508 0.508)
			(layers "F.Cu" "F.Mask" "F.Paste")
			(net "VDD_1.8V")
		)
		(pad "U27" smd circle
			(at 10.500004 0.499999 180)
			(size 0.508 0.508)
			(layers "F.Cu" "F.Mask" "F.Paste")
			(net "VDD_1.8V")
		)
		(pad "U28" smd circle
			(at 11.500002 0.499999 180)
			(size 0.508 0.508)
			(layers "F.Cu" "F.Mask" "F.Paste")
			(net "_NC_SPI3_SCK")
		)
		(pad "U29" smd circle
			(at 12.5 0.499999 180)
			(size 0.508 0.508)
			(layers "F.Cu" "F.Mask" "F.Paste")
			(net "_NFP_SPI2_MOSI")
		)
		(pad "U30" smd circle
			(at 13.499998 0.499999 180)
			(size 0.508 0.508)
			(layers "F.Cu" "F.Mask" "F.Paste")
			(net "_NFP_CFG_SPI_FLASH_MOSI")
		)
		(pad "U31" smd circle
			(at 14.499996 0.499999 180)
			(size 0.508 0.508)
			(layers "F.Cu" "F.Mask" "F.Paste")
			(net "_NFP_ARM_SPI_FLASH_MOSI")
		)
		(pad "U32" smd circle
			(at 15.499994 0.499999 180)
			(size 0.508 0.508)
			(layers "F.Cu" "F.Mask" "F.Paste")
			(net "_NFP_ARM_SPI_FLASH_SEL")
		)
		(pad "V1" smd circle
			(at -15.499994 1.499997 180)
			(size 0.508 0.508)
			(layers "F.Cu" "F.Mask" "F.Paste")
			(net "DDR0_32A_DQ27")
		)
		(pad "V2" smd circle
			(at -14.499996 1.499997 180)
			(size 0.508 0.508)
			(layers "F.Cu" "F.Mask" "F.Paste")
			(net "DDR0_32A_DQ26")
		)
	)
)
